# S9S_MB_2U (Grand Teton) — schematic netlist excerpt (pin names and nets, part order shuffled) for the footprints in the layout excerpt that follows; sources: Cadence DE-HDL packaged netlist, KiCad conversion of 03242023_DA0F0TMBIJ0_F0T_Motherboard_J_brd_V01_OCP.brd

R3881  Q_RES  49.9 1% CHIP  pkg 0402LF  page 88 : A = I3C_SPD_DDRABCD_CPU0_LVC1_SCL_6 ; B = I3C_SPD_DDRABCD_CPU0_LVC1_SCL
PR2526  Q_RES  10 1% EMPTY  pkg 0402LF  page 304 : A = P12V_HSC_SENSE2_N ; B = P12V_HSC_SENSE2_R3_N

(kicad_pcb
	(version 20260206)
	(generator "pcbnew")
	(generator_version "10.0")
	(general
		(thickness 1.6)
		(legacy_teardrops no)
	)
	(paper "A4")
	(title_block
		(title "03242023_DA0F0TMBIJ0_F0T_Motherboard_J_brd_V01_OCP.brd")
		(comment 1 "Grand Teton / footprints 5217-5218 of 6105")
	)
	(layers
		(0 "F.Cu" signal "TOP")
		(4 "In1.Cu" signal "GND")
		(6 "In2.Cu" signal "IN1")
		(8 "In3.Cu" signal "GND1")
		(10 "In4.Cu" signal "IN2")
		(12 "In5.Cu" signal "GND2")
		(14 "In6.Cu" signal "IN3")
		(16 "In7.Cu" signal "GND3")
		(18 "In8.Cu" signal "VCC")
		(20 "In9.Cu" signal "VCC1")
		(22 "In10.Cu" signal "GND4")
		(24 "In11.Cu" signal "IN4")
		(26 "In12.Cu" signal "GND5")
		(28 "In13.Cu" signal "IN5")
		(30 "In14.Cu" signal "GND6")
		(32 "In15.Cu" signal "IN6")
		(34 "In16.Cu" signal "GND7")
		(2 "B.Cu" signal "BOTTOM")
		(9 "F.Adhes" user "F.Adhesive")
		(11 "B.Adhes" user "B.Adhesive")
		(13 "F.Paste" user "Package Geometry/Pastemask Top")
		(15 "B.Paste" user "Package Geometry/Pastemask Bottom")
		(5 "F.SilkS" user "Ref Des/Silkscreen Top")
		(7 "B.SilkS" user "Ref Des/Silkscreen Bottom")
		(1 "F.Mask" user "Board Geometry/Soldermask Top")
		(3 "B.Mask" user "Board Geometry/Soldermask Bottom")
		(17 "Dwgs.User" user "User.Drawings")
		(19 "Cmts.User" user "User.Comments")
		(21 "Eco1.User" user "User.Eco1")
		(23 "Eco2.User" user "User.Eco2")
		(25 "Edge.Cuts" user "Board Geometry/Outline")
		(27 "Margin" user)
		(31 "F.CrtYd" user "Package Geometry/Place Bound Top")
		(29 "B.CrtYd" user "Package Geometry/Place Bound Bottom")
		(35 "F.Fab" user "Ref Des/Assembly Top")
		(33 "B.Fab" user "Ref Des/Assembly Bottom")
	)
	(footprint ""
		(layer "B.Cu")
		(at 294.91813 -400.999452 -90)
		(property "Reference" "PR2526"
			(at 0 0 90)
			(layer "B.SilkS")
			(hide yes)
			(effects
				(font
					(size 1.27 1.27)
				)
				(justify mirror)
			)
		)
		(property "Value" ""
			(at 0 0 90)
			(layer "B.Fab")
			(effects
				(font
					(size 1.27 1.27)
				)
				(justify mirror)
			)
		)
		(duplicate_pad_numbers_are_jumpers no)
		(fp_line
			(start -0.7874 0.4064)
			(end 0.7874 0.4064)
			(stroke
				(width 0.1524)
				(type default)
			)
			(layer "B.SilkS")
		)
		(fp_line
			(start 0.7874 0.4064)
			(end 0.7874 -0.4064)
			(stroke
				(width 0.1524)
				(type default)
			)
			(layer "B.SilkS")
		)
		(fp_line
			(start -0.7874 -0.4064)
			(end -0.7874 0.4064)
			(stroke
				(width 0.1524)
				(type default)
			)
			(layer "B.SilkS")
		)
		(fp_line
			(start 0.7874 -0.4064)
			(end -0.7874 -0.4064)
			(stroke
				(width 0.1524)
				(type default)
			)
			(layer "B.SilkS")
		)
		(fp_line
			(start -0.67945 0.3048)
			(end -0.120396 0.3048)
			(stroke
				(width 0.1)
				(type default)
			)
			(layer "B.Fab")
		)
		(fp_line
			(start -0.120396 0.3048)
			(end -0.120396 0.2794)
			(stroke
				(width 0.1)
				(type default)
			)
			(layer "B.Fab")
		)
		(fp_line
			(start 0.12065 0.3048)
			(end 0.67945 0.3048)
			(stroke
				(width 0.1)
				(type default)
			)
			(layer "B.Fab")
		)
		(fp_line
			(start 0.67945 0.3048)
			(end 0.67945 -0.305054)
			(stroke
				(width 0.1)
				(type default)
			)
			(layer "B.Fab")
		)
		(fp_line
			(start -0.120396 0.2794)
			(end 0.12065 0.2794)
			(stroke
				(width 0.1)
				(type default)
			)
			(layer "B.Fab")
		)
		(fp_line
			(start 0.12065 0.2794)
			(end 0.12065 0.3048)
			(stroke
				(width 0.1)
				(type default)
			)
			(layer "B.Fab")
		)
		(fp_line
			(start -0.12065 -0.2794)
			(end -0.12065 -0.3048)
			(stroke
				(width 0.1)
				(type default)
			)
			(layer "B.Fab")
		)
		(fp_line
			(start 0.12065 -0.2794)
			(end -0.12065 -0.2794)
			(stroke
				(width 0.1)
				(type default)
			)
			(layer "B.Fab")
		)
		(fp_line
			(start -0.67945 -0.3048)
			(end -0.67945 0.3048)
			(stroke
				(width 0.1)
				(type default)
			)
			(layer "B.Fab")
		)
		(fp_line
			(start -0.12065 -0.3048)
			(end -0.67945 -0.3048)
			(stroke
				(width 0.1)
				(type default)
			)
			(layer "B.Fab")
		)
		(fp_line
			(start 0.12065 -0.305054)
			(end 0.12065 -0.2794)
			(stroke
				(width 0.1)
				(type default)
			)
			(layer "B.Fab")
		)
		(fp_line
			(start 0.67945 -0.305054)
			(end 0.12065 -0.305054)
			(stroke
				(width 0.1)
				(type default)
			)
			(layer "B.Fab")
		)
		(pad "1" smd circle
			(at 0.40005 0 90)
			(size 0 0)
			(layers "B.Cu" "B.Mask" "B.Paste")
			(net "P12V_HSC_SENSE2_N")
		)
		(pad "2" smd circle
			(at -0.40005 0 90)
			(size 0 0)
			(layers "B.Cu" "B.Mask" "B.Paste")
			(net "P12V_HSC_SENSE2_R3_N")
		)
	)
	(footprint ""
		(layer "B.Cu")
		(at 256.09169 -318.482726 180)
		(property "Reference" "R3881"
			(at 0 0 0)
			(layer "B.SilkS")
			(hide yes)
			(effects
				(font
					(size 1.27 1.27)
				)
				(justify mirror)
			)
		)
		(property "Value" ""
			(at 0 0 0)
			(layer "B.Fab")
			(effects
				(font
					(size 1.27 1.27)
				)
				(justify mirror)
			)
		)
		(duplicate_pad_numbers_are_jumpers no)
		(fp_line
			(start 0.7874 0.4064)
			(end 0.7874 -0.4064)
			(stroke
				(width 0.1524)
				(type default)
			)
			(layer "B.SilkS")
		)
		(fp_line
			(start 0.7874 -0.4064)
			(end -0.7874 -0.4064)
			(stroke
				(width 0.1524)
				(type default)
			)
			(layer "B.SilkS")
		)
		(fp_line
			(start -0.7874 0.4064)
			(end 0.7874 0.4064)
			(stroke
				(width 0.1524)
				(type default)
			)
			(layer "B.SilkS")
		)
		(fp_line
			(start -0.7874 -0.4064)
			(end -0.7874 0.4064)
			(stroke
				(width 0.1524)
				(type default)
			)
			(layer "B.SilkS")
		)
		(fp_line
			(start 0.67945 0.3048)
			(end 0.67945 -0.305054)
			(stroke
				(width 0.1)
				(type default)
			)
			(layer "B.Fab")
		)
		(fp_line
			(start 0.67945 -0.305054)
			(end 0.12065 -0.305054)
			(stroke
				(width 0.1)
				(type default)
			)
			(layer "B.Fab")
		)
		(fp_line
			(start 0.12065 0.3048)
			(end 0.67945 0.3048)
			(stroke
				(width 0.1)
				(type default)
			)
			(layer "B.Fab")
		)
		(fp_line
			(start 0.12065 0.2794)
			(end 0.12065 0.3048)
			(stroke
				(width 0.1)
				(type default)
			)
			(layer "B.Fab")
		)
		(fp_line
			(start 0.12065 -0.2794)
			(end -0.12065 -0.2794)
			(stroke
				(width 0.1)
				(type default)
			)
			(layer "B.Fab")
		)
		(fp_line
			(start 0.12065 -0.305054)
			(end 0.12065 -0.2794)
			(stroke
				(width 0.1)
				(type default)
			)
			(layer "B.Fab")
		)
		(fp_line
			(start -0.120396 0.3048)
			(end -0.120396 0.2794)
			(stroke
				(width 0.1)
				(type default)
			)
			(layer "B.Fab")
		)
		(fp_line
			(start -0.120396 0.2794)
			(end 0.12065 0.2794)
			(stroke
				(width 0.1)
				(type default)
			)
			(layer "B.Fab")
		)
		(fp_line
			(start -0.12065 -0.2794)
			(end -0.12065 -0.3048)
			(stroke
				(width 0.1)
				(type default)
			)
			(layer "B.Fab")
		)
		(fp_line
			(start -0.12065 -0.3048)
			(end -0.67945 -0.3048)
			(stroke
				(width 0.1)
				(type default)
			)
			(layer "B.Fab")
		)
		(fp_line
			(start -0.67945 0.3048)
			(end -0.120396 0.3048)
			(stroke
				(width 0.1)
				(type default)
			)
			(layer "B.Fab")
		)
		(fp_line
			(start -0.67945 -0.3048)
			(end -0.67945 0.3048)
			(stroke
				(width 0.1)
				(type default)
			)
			(layer "B.Fab")
		)
		(pad "1" smd circle
			(at 0.40005 0)
			(size 0 0)
			(layers "B.Cu" "B.Mask" "B.Paste")
			(net "I3C_SPD_DDRABCD_CPU0_LVC1_SCL_6")
		)
		(pad "2" smd circle
			(at -0.40005 0)
			(size 0 0)
			(layers "B.Cu" "B.Mask" "B.Paste")
			(net "I3C_SPD_DDRABCD_CPU0_LVC1_SCL")
		)
	)
)
